# Bryce Canyon_IOM_M2_Stackup.xlsx — Stack up_16342-2 (pcb-stackup)
|  |  |  |  |  |  | Version |  |  |  |  |  |  |  |  |  |  |  |  |  |  |  |  |  |  |  |
| Board Number: |  | 16342-2 |  |  |  | 02 |  |  |  |  |  |  |  |  |  |  |  |  |  |  |  |  |  |  |  |
| Project name: |  | Bryce Canyon |  |  |  |  |  |  |  |  |  |  |  |  |  |  |  |  |  |  |  |  |  |  |  |
| Model Name: |  | IOM_M.2 |  |  |  |  |  |  |  |  |  |  |  |  |  |  |  |  |  |  |  |  |  |  |  |
| Layer Count: |  | 8 Layer |  |  |  |  |  |  |  |  |  |  |  |  |  |  |  |  |  |  |  |  |  |  |  |
| Date: |  | 2017-09-25 00:00:00 |  |  |  |  |  |  |  |  |  |  |  |  |  |  |  |  |  |  |  |  |  |  |  |
| Loss Material: |  | NPG171+VLP/TU863+VLP  (Tg : 180/Td : 370) |  |  |  |  |  |  | Single Ended Type(mil) |  |  |  |  | Differential Type(mil) |  |  |  |  |  |  |  |  |  |  |  |
| Gold Finger(Y/N): |  | N |  |  |  |  |  | Imp | 50 |  |  |  | Imp | 85 |  |  |  |  |  | 100 |  |  |  |  |  |
| Customer: |  | <name> |  |  |  |  |  | Variation | Inner/Outer+/-5ohm |  |  |  | Variation | Inner/Outer+/-10% |  |  |  |  |  | Inner/Outer+/-10% |  |  |  |  |  |
| EE engineer |  | <name> |  |  |  |  |  | Bus | MISC./I2C |  |  |  | Bus | PCIe/Clock/USB |  |  |  |  |  | Clock/SATA |  |  |  |  |  |
| SI Engineer |  | <name> |  |  |  |  |  |  |  |  |  |  |  |  |  |  |  |  |  |  |  |  |  |  |  |
|  |  |  |  |  |  |  |  | Type | SE |  |  |  | Type | DP |  |  |  |  |  | DP |  |  |  |  |  |
| Layer |  |  | Thickness |  | Glass/Copper Style | Er | Df(1G) | Layers | 1,3,6,8 |  |  |  | Layers | 1,3,6,8 |  |  |  |  |  | 1,3,6,8 |  |  |  |  |  |
|  |  | Cu oz | Wiwynn |  |  | Wiwynn |  |  | Wiwynn |  |  |  |  | Wiwynn |  |  |  |  |  | Wiwynn |  |  |  |  |  |
|  | Mask |  | 0.5 |  |  | 3.4 | 0.025 |  | Width | Imp | Width | Imp |  | Width | Space | Imp | Width | Space | Imp | Width | Space | Imp | Width | Space | Imp |
| Top | Signal | 3/8 oz+plating | 1.7 |  |  |  |  | S1 | 5(L2) | 50.08 |  |  | S1 | 5.75(L2) | 6.5 | 85.36 |  |  |  | 4.9(L2) | 11.1 | 96.82 |  |  |  |
|  | Prepreg |  | 3 |  |  | 3.9 | 0.006 |  |  |  |  |  |  |  |  |  |  |  |  |  |  |  |  |  |  |
| L2 | GND | 1 oz | 1.3 |  |  |  |  | P2 | reference layer |  |  |  | P2 | reference layer |  |  |  |  |  | reference layer |  |  |  |  |  |
|  | Core |  | 4 |  |  | 3.9 | 0.006 |  |  |  |  |  |  |  |  |  |  |  |  |  |  |  |  |  |  |
| L3 | Signal | 1 oz | 1.3 |  |  |  |  | S3 | 5(L2/L4) | 49.28 |  |  | S3 | 5.5(L2/L4) | 7.5 | 84.9 |  |  |  | 4(L2/L4) | 8 | 97.59 |  |  |  |
|  | Prepreg |  | 16.4 |  |  | 4.2 | 0.006 |  |  |  |  |  |  |  |  |  |  |  |  |  |  |  |  |  |  |
| L4 | POWER | 1 oz | 1.3 |  |  |  |  | P4 | reference layer |  |  |  | P4 | reference layer |  |  |  |  |  | reference layer |  |  |  |  |  |
|  | Core |  | 4 |  |  | 3.8 | 0.006 |  |  |  |  |  |  |  |  |  |  |  |  |  |  |  |  |  |  |
| L5 | POWER | 1 oz | 1.3 | 0 | 0 |  |  | P5 | reference layer |  |  |  | P5 | reference layer |  |  |  |  |  | reference layer |  |  |  |  |  |
|  | Prepreg |  | 16.4 | 0 | 0 | 4.2 | 0.006 |  |  |  |  |  |  |  |  |  |  |  |  |  |  |  |  |  |  |
| L6 | Signal | 1 oz | 1.3 | 0 | 0 |  |  | S6 | 5(L5/L7) | 49.28 |  |  | S6 | 5.5(L5/L7) | 7.5 | 84.9 |  |  |  | 4(L5/L7) | 8 | 97.59 |  |  |  |
|  | Core |  | 4 | 0 | 0 | 3.9 | 0.006 |  |  |  |  |  |  |  |  |  |  |  |  |  |  |  |  |  |  |
| L7 | GND | 1 oz | 1.3 | 0 | 0 |  |  | P7 | reference layer |  |  |  | P7 | reference layer |  |  |  |  |  | reference layer |  |  |  |  |  |
|  | Prepreg |  | 3 | 0 | 0 | 3.9 | 0.006 |  |  |  |  |  |  |  |  |  |  |  |  |  |  |  |  |  |  |
| Bottom | Signal | 3/8 oz+plating | 1.7 | 0 | 0 |  |  | S8 | 5(L7) | 50.08 |  |  | S8 | 5.75(L7) | 6.5 | 85.36 |  |  |  | 4.9(L7) | 11.1 | 96.82 |  |  |  |
|  | Mask |  | 0.5 | 0 |  | 3.4 | 0.025 |  |  |  |  |  |  |  |  |  |  |  |  |  |  |  |  |  |  |
| Thickness requirement: 1.6 ± 10% mm |  | mil | 62.99999999999999 |  |  |  |  |  |  |  |  |  |  |  |  |  |  |  |  |  |  |  |  |  |  |
|  |  | mm | 1.6002032004064006 |  |  |  |  |  |  |  |  |  |  |  |  |  |  |  |  |  |  |  |  |  |  |
| Note: | 1. Unit is mil |  |  |  |  |  |  |  |  |  |  |  |  |  |  |  |  |  |  |  |  |  |  |  |  |
|  | 2. The total thickness includes trace and solder mask. |  |  |  |  |  |  |  |  |  |  |  |  |  |  |  |  |  |  |  |  |  |  |  |  |
|  | 3. Minimum hole copper thickness is 1.0 mil. |  |  |  |  |  |  |  |  |  |  |  |  |  |  |  |  |  |  |  |  |  |  |  |  |
|  | 4. Minimum surface copper thickness 1.5 mil. |  |  |  |  |  |  |  |  |  |  |  |  |  |  |  |  |  |  |  |  |  |  |  |  |
|  | 5. If there is no controlled impedance line described as the stackup in the gerber file, PCB supplier can ignore this kind of impedance control directly, but need to inform Wiwynn in engineering question(EQ). |  |  |  |  |  |  |  |  |  |  |  |  |  |  |  |  |  |  |  |  |  |  |  |  |
|  | 6. PCB test coupon requirement and PCB test note are described in the another sheets. |  |  |  |  |  |  |  |  |  |  |  |  |  |  |  |  |  |  |  |  |  |  |  |  |
|  | 7. If there is no "Delta-L" design in gerber file, PCB supplier should design 85 ohm "Delta-L" angle routing coupon and provide the measurement results in FAI report which meet the following criteria: |  |  |  |  |  |  |  |  |  |  |  |  |  |  |  |  |  |  |  |  |  |  |  |  |
|  | For middle-loss material | (Material: NPG171+VLP) |  |  |  |  |  |  |  |  |  |  |  |  |  |  |  |  |  |  |  |  |  |  |  |
|  | (1)   0.69 dB/inch @ 4GHz; 1.38 dB/inch @ 8GHz for microstrip routing |  |  |  |  |  |  |  |  |  |  |  |  |  |  |  |  |  |  |  |  |  |  |  |  |
|  | (2)   0.65 dB/inch @ 4GHz; 1.25 dB/inch @ 8GHz for stripline routing |  |  |  |  |  |  |  |  |  |  |  |  |  |  |  |  |  |  |  |  |  |  |  |  |
|  | For low-loss material | (Material: TU863+VLP) |  |  |  |  |  |  |  |  |  |  |  |  |  |  |  |  |  |  |  |  |  |  |  |
|  | (1)   0.55 dB/inch @ 4GHz; 1.05 dB/inch @ 8GHz for microstrip routing |  |  |  |  |  |  |  |  |  |  |  |  |  |  |  |  |  |  |  |  |  |  |  |  |
|  | (2)   0.48 dB/inch @ 4GHz; 0.9 dB/inch @ 8GHz for stripline routing |  |  |  |  |  |  |  |  |  |  |  |  |  |  |  |  |  |  |  |  |  |  |  |  |
